# SCM (Grand Teton) — schematic netlist excerpt (pin names and nets, part order shuffled) for the footprints in the layout excerpt that follows; sources: Cadence DE-HDL packaged netlist, KiCad conversion of 12092022_DA0F0TMDCD0_F0T_Management_Board_D_brd_V3_OCP.brd

C303  Q_CAP  0.1UF 25V 10% X7R  pkg 0402  page 15 : A = P2V5_SENSOR ; B = GND
C205  Q_CAP  15PF 50V 5% C0G  pkg 0402  page 23 : A = V_DACR ; B = GND
C188  Q_CAP  0.1UF 25V 10% X7R  pkg 0402  page 41 : A = VCCIO2 ; B = GND

(kicad_pcb
	(version 20260206)
	(generator "pcbnew")
	(generator_version "10.0")
	(general
		(thickness 1.6)
		(legacy_teardrops no)
	)
	(paper "A4")
	(title_block
		(title "12092022_DA0F0TMDCD0_F0T_Management_Board_D_brd_V3_OCP.brd")
		(comment 1 "Grand Teton / footprints 1162-1164 of 1440")
	)
	(layers
		(0 "F.Cu" signal "TOP")
		(4 "In1.Cu" signal "GND")
		(6 "In2.Cu" signal "IN1")
		(8 "In3.Cu" signal "GND1")
		(10 "In4.Cu" signal "IN2")
		(12 "In5.Cu" signal "VCC")
		(14 "In6.Cu" signal "VCC1")
		(16 "In7.Cu" signal "IN3")
		(18 "In8.Cu" signal "GND2")
		(20 "In9.Cu" signal "IN4")
		(22 "In10.Cu" signal "GND3")
		(2 "B.Cu" signal "BOTTOM")
		(9 "F.Adhes" user "F.Adhesive")
		(11 "B.Adhes" user "B.Adhesive")
		(13 "F.Paste" user "Package Geometry/Pastemask Top")
		(15 "B.Paste" user "Package Geometry/Pastemask Bottom")
		(5 "F.SilkS" user "Ref Des/Silkscreen Top")
		(7 "B.SilkS" user "Ref Des/Silkscreen Bottom")
		(1 "F.Mask" user "Board Geometry/Soldermask Top")
		(3 "B.Mask" user "Board Geometry/Soldermask Bottom")
		(17 "Dwgs.User" user "User.Drawings")
		(19 "Cmts.User" user "User.Comments")
		(21 "Eco1.User" user "User.Eco1")
		(23 "Eco2.User" user "User.Eco2")
		(25 "Edge.Cuts" user "Board Geometry/Outline")
		(27 "Margin" user)
		(31 "F.CrtYd" user "Package Geometry/Place Bound Top")
		(29 "B.CrtYd" user "Package Geometry/Place Bound Bottom")
		(35 "F.Fab" user "Ref Des/Assembly Top")
		(33 "B.Fab" user "Ref Des/Assembly Bottom")
	)
	(footprint ""
		(layer "B.Cu")
		(at 23.85949 -97.187004)
		(property "Reference" "C188"
			(at 0 0 0)
			(layer "B.SilkS")
			(hide yes)
			(effects
				(font
					(size 1.27 1.27)
				)
				(justify mirror)
			)
		)
		(property "Value" ""
			(at 0 0 0)
			(layer "B.Fab")
			(effects
				(font
					(size 1.27 1.27)
				)
				(justify mirror)
			)
		)
		(duplicate_pad_numbers_are_jumpers no)
		(fp_line
			(start -0.69215 -0.2921)
			(end -0.69215 0.2921)
			(stroke
				(width 0.1524)
				(type default)
			)
			(layer "B.SilkS")
		)
		(fp_line
			(start -0.69215 0.2921)
			(end 0.69215 0.2921)
			(stroke
				(width 0.1524)
				(type default)
			)
			(layer "B.SilkS")
		)
		(fp_line
			(start 0.69215 -0.2921)
			(end -0.69215 -0.2921)
			(stroke
				(width 0.1524)
				(type default)
			)
			(layer "B.SilkS")
		)
		(fp_line
			(start 0.69215 0.2921)
			(end 0.69215 -0.2921)
			(stroke
				(width 0.1524)
				(type default)
			)
			(layer "B.SilkS")
		)
		(fp_line
			(start -0.51435 -0.2794)
			(end -0.51435 0.2794)
			(stroke
				(width 0.1)
				(type default)
			)
			(layer "B.Fab")
		)
		(fp_line
			(start -0.51435 0.2794)
			(end 0.51435 0.2794)
			(stroke
				(width 0.1)
				(type default)
			)
			(layer "B.Fab")
		)
		(fp_line
			(start 0.51435 -0.2794)
			(end -0.51435 -0.2794)
			(stroke
				(width 0.1)
				(type default)
			)
			(layer "B.Fab")
		)
		(fp_line
			(start 0.51435 0.2794)
			(end 0.51435 -0.2794)
			(stroke
				(width 0.1)
				(type default)
			)
			(layer "B.Fab")
		)
		(pad "1" smd circle
			(at 0.40005 0 180)
			(size 0 0)
			(layers "B.Cu" "B.Mask" "B.Paste")
			(net "VCCIO2")
		)
		(pad "2" smd circle
			(at -0.40005 0 180)
			(size 0 0)
			(layers "B.Cu" "B.Mask" "B.Paste")
			(net "GND")
		)
		(zone
			(layer "B.Cu")
			(hatch none 0.5)
			(connect_pads
				(clearance 0)
			)
			(min_thickness 0.25)
			(keepout
				(tracks not_allowed)
				(vias allowed)
				(pads allowed)
				(copperpour not_allowed)
				(footprints allowed)
			)
			(placement
				(enabled no)
				(sheetname "")
			)
			(fill
				(thermal_gap 0.5)
				(thermal_bridge_width 0.5)
				(island_removal_mode 0)
			)
			(polygon
				(pts
					(xy 24.04999 -97.099374) (xy 23.95855 -97.041208) (xy 23.75916 -97.041208) (xy 23.66899 -97.099374)
					(xy 23.66899 -97.274634) (xy 23.75916 -97.333054) (xy 23.95855 -97.333054) (xy 24.04999 -97.274888)
				)
			)
		)
	)
	(footprint ""
		(layer "B.Cu")
		(at 28.575 -32.385 90)
		(property "Reference" "C205"
			(at 0 0 90)
			(layer "B.SilkS")
			(hide yes)
			(effects
				(font
					(size 1.27 1.27)
				)
				(justify mirror)
			)
		)
		(property "Value" ""
			(at 0 0 90)
			(layer "B.Fab")
			(effects
				(font
					(size 1.27 1.27)
				)
				(justify mirror)
			)
		)
		(duplicate_pad_numbers_are_jumpers no)
		(fp_line
			(start 0.7874 -0.4064)
			(end -0.7874 -0.4064)
			(stroke
				(width 0.1524)
				(type default)
			)
			(layer "B.SilkS")
		)
		(fp_line
			(start -0.7874 -0.4064)
			(end -0.7874 0.4064)
			(stroke
				(width 0.1524)
				(type default)
			)
			(layer "B.SilkS")
		)
		(fp_line
			(start 0.7874 0.4064)
			(end 0.7874 -0.4064)
			(stroke
				(width 0.1524)
				(type default)
			)
			(layer "B.SilkS")
		)
		(fp_line
			(start -0.7874 0.4064)
			(end 0.7874 0.4064)
			(stroke
				(width 0.1524)
				(type default)
			)
			(layer "B.SilkS")
		)
		(fp_line
			(start 0.67945 -0.305054)
			(end 0.12065 -0.305054)
			(stroke
				(width 0.1)
				(type default)
			)
			(layer "B.Fab")
		)
		(fp_line
			(start 0.12065 -0.305054)
			(end 0.12065 -0.2794)
			(stroke
				(width 0.1)
				(type default)
			)
			(layer "B.Fab")
		)
		(fp_line
			(start -0.12065 -0.3048)
			(end -0.67945 -0.3048)
			(stroke
				(width 0.1)
				(type default)
			)
			(layer "B.Fab")
		)
		(fp_line
			(start -0.67945 -0.3048)
			(end -0.67945 0.3048)
			(stroke
				(width 0.1)
				(type default)
			)
			(layer "B.Fab")
		)
		(fp_line
			(start 0.12065 -0.2794)
			(end -0.12065 -0.2794)
			(stroke
				(width 0.1)
				(type default)
			)
			(layer "B.Fab")
		)
		(fp_line
			(start -0.12065 -0.2794)
			(end -0.12065 -0.3048)
			(stroke
				(width 0.1)
				(type default)
			)
			(layer "B.Fab")
		)
		(fp_line
			(start 0.12065 0.2794)
			(end 0.12065 0.3048)
			(stroke
				(width 0.1)
				(type default)
			)
			(layer "B.Fab")
		)
		(fp_line
			(start -0.120396 0.2794)
			(end 0.12065 0.2794)
			(stroke
				(width 0.1)
				(type default)
			)
			(layer "B.Fab")
		)
		(fp_line
			(start 0.67945 0.3048)
			(end 0.67945 -0.305054)
			(stroke
				(width 0.1)
				(type default)
			)
			(layer "B.Fab")
		)
		(fp_line
			(start 0.12065 0.3048)
			(end 0.67945 0.3048)
			(stroke
				(width 0.1)
				(type default)
			)
			(layer "B.Fab")
		)
		(fp_line
			(start -0.120396 0.3048)
			(end -0.120396 0.2794)
			(stroke
				(width 0.1)
				(type default)
			)
			(layer "B.Fab")
		)
		(fp_line
			(start -0.67945 0.3048)
			(end -0.120396 0.3048)
			(stroke
				(width 0.1)
				(type default)
			)
			(layer "B.Fab")
		)
		(pad "1" smd circle
			(at 0.40005 0 270)
			(size 0 0)
			(layers "B.Cu" "B.Mask" "B.Paste")
			(net "V_DACR")
		)
		(pad "2" smd circle
			(at -0.40005 0 270)
			(size 0 0)
			(layers "B.Cu" "B.Mask" "B.Paste")
			(net "GND")
		)
	)
	(footprint ""
		(layer "B.Cu")
		(at 53.291994 -69.397372 -90)
		(property "Reference" "C303"
			(at 0 0 90)
			(layer "B.SilkS")
			(hide yes)
			(effects
				(font
					(size 1.27 1.27)
				)
				(justify mirror)
			)
		)
		(property "Value" ""
			(at 0 0 90)
			(layer "B.Fab")
			(effects
				(font
					(size 1.27 1.27)
				)
				(justify mirror)
			)
		)
		(duplicate_pad_numbers_are_jumpers no)
		(fp_line
			(start -0.7874 0.4064)
			(end 0.7874 0.4064)
			(stroke
				(width 0.1524)
				(type default)
			)
			(layer "B.SilkS")
		)
		(fp_line
			(start 0.7874 0.4064)
			(end 0.7874 -0.4064)
			(stroke
				(width 0.1524)
				(type default)
			)
			(layer "B.SilkS")
		)
		(fp_line
			(start -0.7874 -0.4064)
			(end -0.7874 0.4064)
			(stroke
				(width 0.1524)
				(type default)
			)
			(layer "B.SilkS")
		)
		(fp_line
			(start 0.7874 -0.4064)
			(end -0.7874 -0.4064)
			(stroke
				(width 0.1524)
				(type default)
			)
			(layer "B.SilkS")
		)
		(fp_line
			(start -0.67945 0.3048)
			(end -0.120396 0.3048)
			(stroke
				(width 0.1)
				(type default)
			)
			(layer "B.Fab")
		)
		(fp_line
			(start -0.120396 0.3048)
			(end -0.120396 0.2794)
			(stroke
				(width 0.1)
				(type default)
			)
			(layer "B.Fab")
		)
		(fp_line
			(start 0.12065 0.3048)
			(end 0.67945 0.3048)
			(stroke
				(width 0.1)
				(type default)
			)
			(layer "B.Fab")
		)
		(fp_line
			(start 0.67945 0.3048)
			(end 0.67945 -0.305054)
			(stroke
				(width 0.1)
				(type default)
			)
			(layer "B.Fab")
		)
		(fp_line
			(start -0.120396 0.2794)
			(end 0.12065 0.2794)
			(stroke
				(width 0.1)
				(type default)
			)
			(layer "B.Fab")
		)
		(fp_line
			(start 0.12065 0.2794)
			(end 0.12065 0.3048)
			(stroke
				(width 0.1)
				(type default)
			)
			(layer "B.Fab")
		)
		(fp_line
			(start -0.12065 -0.2794)
			(end -0.12065 -0.3048)
			(stroke
				(width 0.1)
				(type default)
			)
			(layer "B.Fab")
		)
		(fp_line
			(start 0.12065 -0.2794)
			(end -0.12065 -0.2794)
			(stroke
				(width 0.1)
				(type default)
			)
			(layer "B.Fab")
		)
		(fp_line
			(start -0.67945 -0.3048)
			(end -0.67945 0.3048)
			(stroke
				(width 0.1)
				(type default)
			)
			(layer "B.Fab")
		)
		(fp_line
			(start -0.12065 -0.3048)
			(end -0.67945 -0.3048)
			(stroke
				(width 0.1)
				(type default)
			)
			(layer "B.Fab")
		)
		(fp_line
			(start 0.12065 -0.305054)
			(end 0.12065 -0.2794)
			(stroke
				(width 0.1)
				(type default)
			)
			(layer "B.Fab")
		)
		(fp_line
			(start 0.67945 -0.305054)
			(end 0.12065 -0.305054)
			(stroke
				(width 0.1)
				(type default)
			)
			(layer "B.Fab")
		)
		(pad "1" smd circle
			(at 0.40005 0 90)
			(size 0 0)
			(layers "B.Cu" "B.Mask" "B.Paste")
			(net "P2V5_SENSOR")
		)
		(pad "2" smd circle
			(at -0.40005 0 90)
			(size 0 0)
			(layers "B.Cu" "B.Mask" "B.Paste")
			(net "GND")
		)
	)
)
